# SCM (Grand Teton) — schematic netlist excerpt (pin names and nets, part order shuffled) for the footprints in the layout excerpt that follows; sources: Cadence DE-HDL packaged netlist, KiCad conversion of 12092022_DA0F0TMDCD0_F0T_Management_Board_D_brd_V3_OCP.brd

X14  TP_TDR_4P_FTS  TP_TDR_4P_DIP EMPTY  pkg TH  page 60
  S1  = TDR_DIFF_100_IN1_DP
  P1  = GND_P1
  P2  = GND_P1
  S2  = TDR_DIFF_100_IN1_DN

R397  Q_RES  0 5% CHIP  pkg 0402LF  page 34 : A = JTAG_SCM_PLD_R_JTAGEN ; B = JTAG_SCM_PLD_JTAGEN

(kicad_pcb
	(version 20260206)
	(generator "pcbnew")
	(generator_version "10.0")
	(general
		(thickness 1.6)
		(legacy_teardrops no)
	)
	(paper "A4")
	(title_block
		(title "12092022_DA0F0TMDCD0_F0T_Management_Board_D_brd_V3_OCP.brd")
		(comment 1 "Grand Teton / footprints 1276-1277 of 1440")
	)
	(layers
		(0 "F.Cu" signal "TOP")
		(4 "In1.Cu" signal "GND")
		(6 "In2.Cu" signal "IN1")
		(8 "In3.Cu" signal "GND1")
		(10 "In4.Cu" signal "IN2")
		(12 "In5.Cu" signal "VCC")
		(14 "In6.Cu" signal "VCC1")
		(16 "In7.Cu" signal "IN3")
		(18 "In8.Cu" signal "GND2")
		(20 "In9.Cu" signal "IN4")
		(22 "In10.Cu" signal "GND3")
		(2 "B.Cu" signal "BOTTOM")
		(9 "F.Adhes" user "F.Adhesive")
		(11 "B.Adhes" user "B.Adhesive")
		(13 "F.Paste" user "Package Geometry/Pastemask Top")
		(15 "B.Paste" user "Package Geometry/Pastemask Bottom")
		(5 "F.SilkS" user "Ref Des/Silkscreen Top")
		(7 "B.SilkS" user "Ref Des/Silkscreen Bottom")
		(1 "F.Mask" user "Board Geometry/Soldermask Top")
		(3 "B.Mask" user "Board Geometry/Soldermask Bottom")
		(17 "Dwgs.User" user "User.Drawings")
		(19 "Cmts.User" user "User.Comments")
		(21 "Eco1.User" user "User.Eco1")
		(23 "Eco2.User" user "User.Eco2")
		(25 "Edge.Cuts" user "Board Geometry/Outline")
		(27 "Margin" user)
		(31 "F.CrtYd" user "Package Geometry/Place Bound Top")
		(29 "B.CrtYd" user "Package Geometry/Place Bound Bottom")
		(35 "F.Fab" user "Ref Des/Assembly Top")
		(33 "B.Fab" user "Ref Des/Assembly Bottom")
	)
	(footprint ""
		(layer "B.Cu")
		(at 112.014 54.61 90)
		(property "Reference" "X14"
			(at 1.73863 3.2385 0)
			(unlocked yes)
			(layer "B.SilkS")
			(effects
				(font
					(size 0.7874 0.5842)
					(thickness 0.1524)
				)
				(justify left mirror)
			)
		)
		(property "Value" ""
			(at 0 0 90)
			(layer "B.Fab")
			(effects
				(font
					(size 1.27 1.27)
				)
				(justify mirror)
			)
		)
		(property "Device Type" "TP_TDR_4P_FTS_TH-TP_TDR_4P_DIPA"
			(at -1.30175 1.27 0)
			(unlocked yes)
			(layer "B.Fab")
			(hide yes)
			(effects
				(font
					(size 0.635 0.4064)
					(thickness 0.1524)
				)
				(justify mirror)
			)
		)
		(property "User Part Number" "N_A"
			(at -1.30175 1.27 0)
			(unlocked yes)
			(layer "Cmts.User")
			(hide yes)
			(effects
				(font
					(size 0.635 0.4064)
					(thickness 0.1524)
				)
				(justify mirror)
			)
		)
		(duplicate_pad_numbers_are_jumpers no)
		(fp_line
			(start 0 -1.27)
			(end 0 -0.635)
			(stroke
				(width 0.1524)
				(type default)
			)
			(layer "B.SilkS")
		)
		(fp_line
			(start -2.54 -1.27)
			(end 0 -1.27)
			(stroke
				(width 0.1524)
				(type default)
			)
			(layer "B.SilkS")
		)
		(fp_line
			(start -2.54 -1.1303)
			(end -2.54 -1.27)
			(stroke
				(width 0.1524)
				(type default)
			)
			(layer "B.SilkS")
		)
		(fp_line
			(start 0 0.635)
			(end 0 1.905)
			(stroke
				(width 0.1524)
				(type default)
			)
			(layer "B.SilkS")
		)
		(fp_line
			(start -2.54 1.4097)
			(end -2.54 1.1303)
			(stroke
				(width 0.1524)
				(type default)
			)
			(layer "B.SilkS")
		)
		(fp_line
			(start 0 3.175)
			(end 0 3.81)
			(stroke
				(width 0.1524)
				(type default)
			)
			(layer "B.SilkS")
		)
		(fp_line
			(start 0 3.81)
			(end -2.54 3.81)
			(stroke
				(width 0.1524)
				(type default)
			)
			(layer "B.SilkS")
		)
		(fp_line
			(start -2.54 3.81)
			(end -2.54 3.6703)
			(stroke
				(width 0.1524)
				(type default)
			)
			(layer "B.SilkS")
		)
		(fp_poly
			(pts
				(xy 0.761746 0) (xy 2.285746 -0.762) (xy 2.285746 0.762)
			)
			(stroke
				(width 0)
				(type default)
			)
			(fill yes)
			(layer "B.SilkS")
		)
		(fp_line
			(start 0 -1.27)
			(end 0 3.81)
			(stroke
				(width 0.1)
				(type default)
			)
			(layer "B.Fab")
		)
		(fp_line
			(start -2.54 -1.27)
			(end 0 -1.27)
			(stroke
				(width 0.1)
				(type default)
			)
			(layer "B.Fab")
		)
		(fp_line
			(start 0 3.81)
			(end -2.54 3.81)
			(stroke
				(width 0.1)
				(type default)
			)
			(layer "B.Fab")
		)
		(fp_line
			(start -2.54 3.81)
			(end -2.54 -1.27)
			(stroke
				(width 0.1)
				(type default)
			)
			(layer "B.Fab")
		)
		(fp_poly
			(pts
				(xy 0.761746 0) (xy 2.285746 -0.762) (xy 2.285746 0.762)
			)
			(stroke
				(width 0)
				(type default)
			)
			(fill yes)
			(layer "B.Fab")
		)
		(pad "1" thru_hole circle
			(at 0 0 270)
			(size 1.0033 1.0033)
			(drill 0.249936)
			(layers "*.Cu" "*.Mask")
			(remove_unused_layers no)
			(net "TDR_DIFF_100_IN1_DP")
			(clearance 0.10795)
			(padstack
				(mode front_inner_back)
				(layer "Inner"
					(shape circle)
					(size 0.8001 0.8001)
					(clearance 0.1524)
				)
				(layer "B.Cu"
					(shape circle)
					(size 1.0033 1.0033)
					(thermal_gap 0.10795)
					(clearance 0.10795)
				)
			)
		)
		(pad "2" thru_hole circle
			(at -2.54 0 270)
			(size 1.9939 1.9939)
			(drill 0.249936)
			(layers "*.Cu" "*.Mask")
			(remove_unused_layers no)
			(net "GND_P1")
			(clearance 0.10795)
			(padstack
				(mode front_inner_back)
				(layer "Inner"
					(shape circle)
					(size 0.8001 0.8001)
					(clearance 0.1524)
				)
				(layer "B.Cu"
					(shape circle)
					(size 1.9939 1.9939)
					(thermal_gap 0.10795)
					(clearance 0.10795)
				)
			)
		)
		(pad "3" thru_hole circle
			(at -2.54 2.54 270)
			(size 1.9939 1.9939)
			(drill 0.249936)
			(layers "*.Cu" "*.Mask")
			(remove_unused_layers no)
			(net "GND_P1")
			(clearance 0.10795)
			(padstack
				(mode front_inner_back)
				(layer "Inner"
					(shape circle)
					(size 0.8001 0.8001)
					(clearance 0.1524)
				)
				(layer "B.Cu"
					(shape circle)
					(size 1.9939 1.9939)
					(thermal_gap 0.10795)
					(clearance 0.10795)
				)
			)
		)
		(pad "4" thru_hole circle
			(at 0 2.54 270)
			(size 1.0033 1.0033)
			(drill 0.249936)
			(layers "*.Cu" "*.Mask")
			(remove_unused_layers no)
			(net "TDR_DIFF_100_IN1_DN")
			(clearance 0.10795)
			(padstack
				(mode front_inner_back)
				(layer "Inner"
					(shape circle)
					(size 0.8001 0.8001)
					(clearance 0.1524)
				)
				(layer "B.Cu"
					(shape circle)
					(size 1.0033 1.0033)
					(thermal_gap 0.10795)
					(clearance 0.10795)
				)
			)
		)
	)
	(footprint ""
		(layer "B.Cu")
		(at 17.2974 -83.693 90)
		(property "Reference" "R397"
			(at 0 0 90)
			(layer "B.SilkS")
			(hide yes)
			(effects
				(font
					(size 1.27 1.27)
				)
				(justify mirror)
			)
		)
		(property "Value" ""
			(at 0 0 90)
			(layer "B.Fab")
			(effects
				(font
					(size 1.27 1.27)
				)
				(justify mirror)
			)
		)
		(duplicate_pad_numbers_are_jumpers no)
		(fp_line
			(start 0.7874 -0.4064)
			(end -0.7874 -0.4064)
			(stroke
				(width 0.1524)
				(type default)
			)
			(layer "B.SilkS")
		)
		(fp_line
			(start -0.7874 -0.4064)
			(end -0.7874 0.4064)
			(stroke
				(width 0.1524)
				(type default)
			)
			(layer "B.SilkS")
		)
		(fp_line
			(start 0.7874 0.4064)
			(end 0.7874 -0.4064)
			(stroke
				(width 0.1524)
				(type default)
			)
			(layer "B.SilkS")
		)
		(fp_line
			(start -0.7874 0.4064)
			(end 0.7874 0.4064)
			(stroke
				(width 0.1524)
				(type default)
			)
			(layer "B.SilkS")
		)
		(fp_line
			(start 0.67945 -0.305054)
			(end 0.12065 -0.305054)
			(stroke
				(width 0.1)
				(type default)
			)
			(layer "B.Fab")
		)
		(fp_line
			(start 0.12065 -0.305054)
			(end 0.12065 -0.2794)
			(stroke
				(width 0.1)
				(type default)
			)
			(layer "B.Fab")
		)
		(fp_line
			(start -0.12065 -0.3048)
			(end -0.67945 -0.3048)
			(stroke
				(width 0.1)
				(type default)
			)
			(layer "B.Fab")
		)
		(fp_line
			(start -0.67945 -0.3048)
			(end -0.67945 0.3048)
			(stroke
				(width 0.1)
				(type default)
			)
			(layer "B.Fab")
		)
		(fp_line
			(start 0.12065 -0.2794)
			(end -0.12065 -0.2794)
			(stroke
				(width 0.1)
				(type default)
			)
			(layer "B.Fab")
		)
		(fp_line
			(start -0.12065 -0.2794)
			(end -0.12065 -0.3048)
			(stroke
				(width 0.1)
				(type default)
			)
			(layer "B.Fab")
		)
		(fp_line
			(start 0.12065 0.2794)
			(end 0.12065 0.3048)
			(stroke
				(width 0.1)
				(type default)
			)
			(layer "B.Fab")
		)
		(fp_line
			(start -0.120396 0.2794)
			(end 0.12065 0.2794)
			(stroke
				(width 0.1)
				(type default)
			)
			(layer "B.Fab")
		)
		(fp_line
			(start 0.67945 0.3048)
			(end 0.67945 -0.305054)
			(stroke
				(width 0.1)
				(type default)
			)
			(layer "B.Fab")
		)
		(fp_line
			(start 0.12065 0.3048)
			(end 0.67945 0.3048)
			(stroke
				(width 0.1)
				(type default)
			)
			(layer "B.Fab")
		)
		(fp_line
			(start -0.120396 0.3048)
			(end -0.120396 0.2794)
			(stroke
				(width 0.1)
				(type default)
			)
			(layer "B.Fab")
		)
		(fp_line
			(start -0.67945 0.3048)
			(end -0.120396 0.3048)
			(stroke
				(width 0.1)
				(type default)
			)
			(layer "B.Fab")
		)
		(pad "1" smd circle
			(at 0.40005 0 270)
			(size 0 0)
			(layers "B.Cu" "B.Mask" "B.Paste")
			(net "JTAG_SCM_PLD_R_JTAGEN")
		)
		(pad "2" smd circle
			(at -0.40005 0 270)
			(size 0 0)
			(layers "B.Cu" "B.Mask" "B.Paste")
			(net "JTAG_SCM_PLD_JTAGEN")
		)
	)
)
